# Primary and Alternate BOM of B91.01110.0016_RDPB.xls — Sheet0 (bom)
| Part Number | B91.01110.0016 |  |  |  |  |  |  |  |  |  |  |  |  |
| Revision | D |  |  |  |  |  |  |  |  |  |  |  |  |
| Sequence | 1 |  |  |  |  |  |  |  |  |  |  |  |  |
| Description | BRYCE CANYON REAR DPB GCE-1 PD-P MAIN |  |  |  |  |  |  |  |  |  |  |  |  |
| Project Code | BPD011010001 |  |  |  |  |  |  |  |  |  |  |  |  |
| Latest Revision? | YES |  |  |  |  |  |  |  |  |  |  |  |  |
| PDM BOM List |  |  |  |  |  |  |  |  |  |  |  |  |  |
| Level | Parent Number | Part Number | Description | Green Factor | Manufacturer | Manufacturer Part Number | Source | BOM Usage | M/P Code | S/D | Qty | UoM | Location |
| 1 | B91.01110.0016 | B55.01103.0003 | BRYCE CANYON REAR DPB GCE-1 PD-P MAIN(D) | R2; |  |  |  | M | Manufacture |  | 1 | PCS |  |
| 2 | B55.01103.0003 | 020.8000B.0056 | CONN CTR 56P 10106121-7000401LF, HTN | R2_SA; | FCI | 10106121-7000401LF | Multiple |  | Purchase | DIP | 1 | PCS | BUS1 |
| A(Alternative to previous component) | B55.01103.0003 | 020.80992.0056 | CONN CTR PRESFIT 56P 6450824-9 | R2_SA; | TE | 6450824-9 |  |  | Purchase |  |  |  |  |
| 2 | B55.01103.0003 | 020.80417.0001 | CONN CTR XCEDE 968-3200-A1H, LCP | R2_SA;HF_SA; | AMPHENOL | 968-3200-A1H | Single |  | Purchase | DIP | 1 | PCS | PWR1 |
| 2 | B55.01103.0003 | 020.80657.0001 | CONN PWR XCEDE JX412-50194 | R2_SA;HF_SA; | AMPHENOL | JX412-50194 | Single |  | Purchase | DIP | 1 | PCS | DPB2 |
| 2 | B55.01103.0003 | 020.80666.0010 | CONN CTR 10P RT 15-24-6103 | R2_SA;HF_SA; | MOLEX | 15-24-6103 | Single |  | Purchase | DIP | 4 | PCS | FAN1 FAN2 FAN3 FAN4 |
| 2 | B55.01103.0003 | 020.80829.0001 | CONN SIGNAL XCEDE JX410-50839_REVA | R2_SA; | AMPHENOL | JX410-50839_RevA | Single |  | Purchase | DIP | 1 | PCS | DPB1 |
| 2 | B55.01103.0003 | 020.80946.0001 | CONN XCEDE JX924-3405-505_REVA | R2_SA;HF_SA; | AMPHENOL | C-924-3405-505_RevA | Single |  | Purchase | DIP | 1 | PCS |  |
| 2 | B55.01103.0003 | 020.80956.0001 | CONN SIGNAL XCEDE 923-3L0E-40H,LCP | R2_SA;HF_SA; | AMPHENOL | 923-3L0E-40H | Single |  | Purchase | DIP | 1 | PCS |  |
| 2 | B55.01103.0003 | 020.80957.0001 | CONN SIGNAL XCEDE 923-300C-40H,LCP | R2_SA;HF_SA; | AMPHENOL | 923-300C-40H | Single |  | Purchase | DIP | 1 | PCS |  |
| 2 | B55.01103.0003 | 020.80958.0001 | CONN SIGNAL XCEDE  923-300E-40H,LCP | R2_SA;HF_SA; | AMPHENOL | 923-300E-40H | Single |  | Purchase | DIP | 2 | PCS |  |
| 2 | B55.01103.0003 | 020.80961.0001 | CONN SIGNAL XCEDE 923-310E-30H | R2_SA;HF_SA; | AMPHENOL | 923-310E-30H | Single |  | Purchase | DIP | 1 | PCS | PCIE1 |
| 2 | B55.01103.0003 | 06.WP130.14A | LED BLUE/YELLOW WP130WDT-TD88 3P DIP | R2_SA;HF_SA; | KINGBRIGHT | WP130WDT-TD88 | Single |  | Purchase | DIP | 4 | PCS | FLED1 FLED2 FLED3 FLED4 |
| 2 | B55.01103.0003 | 086.000BF.0G20 | SCRW #2-56_L3_8_INCH 577-0014-000 | R2_SA;HF_SA; | AMPHENOL | 086.000BF.0G20 | Single |  | Purchase | DIP | 1 | PCS |  |
| 2 | B55.01103.0003 | 086.000LQ.0543 | THUMB SCREW PRESSFIT M3 L3 BC | R2_SA;HF_SA; | FIVETECH | 27-141-201-5 | Single |  | Purchase | DIP | 2 | PCS |  |
| 2 | B55.01103.0003 | 086.1A554.0140 | SCRW PAN M3X0.5 L14 NI NYLOK | R2_SA;HF_SA; | WENHAO | 086.1A554.0140 | Single |  | Purchase | DIP | 2 | PCS |  |
| 2 | B55.01103.0003 | 088.0000E.0140 | WASH NYLON WS6-3.2-1 | R2_SA;HF_SA; | KANGYANG | WS6-3.2-1 | Single |  | Purchase | DIP | 2 | PCS |  |
| 2 | B55.01103.0003 | 40.58D03.001 | LBL POLYIMIDE31.8*6.35 BARCODE | R2_SA;HF_SA;G_SA; | LABELJET | 40.58D03.001 | Single |  | Purchase | DIP | 2 | PCS |  |
| 2 | B55.01103.0003 | 40.6E727.001 | LBL 50X15MM BLANK WHITE POLYESTER | R2_SA;HF_SA; | WISTRON | 40.6E727.001 | Single |  | Purchase | DIP | 1 | PCS |  |
| 2 | B55.01103.0003 | 640.00X01.0001 | LBL 7X7MM  FOR SONIC | R2_SA;HF_SA; | WISTRON | 640.00X01.0001 | Single |  | Purchase | DIP | 1 | PCS |  |
| 2 | B55.01103.0003 | 87.41242.420 | NUT M3 PLASMA | R2_SA;HF_SA; | WENHAO | 87.41242.420 | Single |  | Purchase | DIP | 2 | PCS |  |
| 2 | B55.01103.0003 | B42.01101.0001 | GUIDE PIN 914-3000-00A | R2_SA;HF_SA; | AMPHENOL | B42.01101.0001 | Single |  | Purchase | DIP | 1 | PCS |  |
| 2 | B55.01103.0003 | B42.0111J.1001 | CVR XCEDE PWR JX412-50194 MP | R2_SA;HF_SA; | KANGYANG | COVER-15 | Multiple |  | Purchase | DIP | 1 | PCS |  |
| A | B55.01103.0003 | B42.0111J.0001 | CVR XCEDE PWR JX412-50194 | R2_SA;HF_SA; | KANGYANG | COVER-15 |  |  | Purchase |  |  |  |  |
| 2 | B55.01103.0003 | B42.0111L.1001 | CVR XCEDE SIGNAL JX410-50839 MP | R2_SA;HF_SA; | KANGYANG | COVER-17 | Multiple |  | Purchase | DIP | 1 | PCS |  |
| A | B55.01103.0003 | B42.0111L.0001 | CVR XCEDE SIGNAL JX410-50839 | R2_SA;HF_SA; | KANGYANG | COVER-17 |  |  | Purchase |  |  |  |  |
| 2 | B55.01103.0003 | B55.01103.M003 | BRYCE CANYON REAR DPB GCE-1 PD-P MAIN(S) | R2; |  |  |  | M | Manufacture | DIP | 1 | PCS |  |
| 3 | B55.01103.M003 | 056.15005.0001 | IR RECV PHOTOTANSISTOR AA4040P3S | R2_SA;HF_SA; | KINGBRIGHT | AA4040P3S | Single |  | Purchase | SMT | 1 | PCS | Q208 |
| 3 | B55.01103.M003 | 062.10010.0121 | SKT SAS S14+P15 10125550-001C-TRLF ,LCP | R2_SA;HF_SA; | FCI | 10125550-001C-TRLF | Multiple |  | Purchase | SMT | 36 | PCS | HDDSAS0 HDDSAS1 HDDSAS10 HDDSAS11 HDDSAS12 HDDSAS13 HDDSAS14 HDDSAS15 HDDSAS16 HDDSAS17 HDDSAS18 HDDSAS19 HDDSAS2 HDDSAS20 HDDSAS21 HDDSAS22 HDDSAS23 HDDSAS24 HDDSAS25 HDDSAS26 HDDSAS27 HDDSAS28 HDDSAS29 HDDSAS3 HDDSAS30 HDDSAS31 HDDSAS32 HDDSAS33 HDDSAS34 HDDSAS35 HDDSAS4 HDDSAS5 HDDSAS6 HDDSAS7 HDDSAS8 HDDSAS9 |
| A | B55.01103.M003 | 62.10108.111 | SKT SAS S14+P15 SAS-F313-014-1-TR SMD | R2_SA;HF_SA; | AMPHENOL | SAS-F313-014-1-TR |  |  | Purchase |  |  |  |  |
| 3 | B55.01103.M003 | 064.0U305.0C0N | CHIP RES 0.0003 F 3W 4026 | R2_SA;HF_SA; | VISHAY | WSL4026L3000FEA | Single |  | Purchase | SMT | 3 | PCS | R1009 R1012 R1047 |
| 3 | B55.01103.M003 | 064.71525.06DS | CHIP RES 71.5K F 1/16W 0402 | R2_SA;HF_SA;G_SA; | YAGEO;KOA | RC0402FR-0771K5L;RK73H1ETQTP7152F | Multiple |  | Purchase | SMT | 4 | PCS | R1109 R1127 R1147 R1166 |
| 3 | B55.01103.M003 | 064.86625.06DS | CHIP RES 86.6K F 1/16W 0402 | R2_SA;HF_SA;G_SA; | YAGEO;KOA | RC0402FR-0786K6L;RK73H1ETQTP8662F | Multiple |  | Purchase | SMT | 1 | PCS | R1006 |
| 3 | B55.01103.M003 | 071.00128.000W | IC ADC SYS ADC128D818CIMTX/NOPB TSSOP16P | R2_SA;HF_SA; | TI | ADC128D818CIMTX/NOPB | Single |  | Purchase | SMT | 1 | PCS | U14 |
| 3 | B55.01103.M003 | 071.09555.000W | IC I/O EXPANDER TCA9555PWR TSSOP 24P | R2_SA;HF_SA; | TI | TCA9555PWR | Multiple |  | Purchase | SMT | 7 | PCS | U3 U4 U5 U6 U7 U8 U9 |
| A | B55.01103.M003 | 71.09555.B0W | IC IO PCA9555PWRG4 TSSOP 24P | R2_SA;HF_SA; | TI | PCA9555PWRG4 |  |  | Purchase |  |  |  |  |
| 3 | B55.01103.M003 | 074.01278.0A7Z | IC SWAP CTRL ADM1278-2ACPZ-RL LFCSP 32P | R2_SA;HF_SA; | ADI | ADM1278-2ACPZ-RL | Single |  | Purchase | SMT | 2 | PCS | U21 U22 |
| 3 | B55.01103.M003 | 074.09077.003F | IC LDO REQULATOR RT9077-33GJ5 TSOT-23-5 | R2_SA;HF_SA; | RICHTEK | RT9077-33GJ5 | Multiple |  | Purchase | SMT | 1 | PCS | U48 |
| A | B55.01103.M003 | 074.09067.003F | IC LDO RT9067-33GB SOT-23-5 | R2_SA;HF_SA; | RICHTEK | RT9067-33GB |  |  | Purchase |  |  |  |  |
| 3 | B55.01103.M003 | 074.31790.0073 | IC FAN CTRL MAX31790ATI+T TQFN-EP 28P | R2_SA;HF_SA; | MAXIM | MAX31790ATI+T | Single |  | Purchase | SMT | 2 | PCS | U29 U30 |
| 3 | B55.01103.M003 | 075.00639.007C | IC FET MOS SSM6P39TU 6P, UF6 | R2_SA;HF_SA; | TOSHIBA | SSM6P39TU | Multiple |  | Purchase | SMT | 4 | PCS | Q204 Q205 Q206 Q207 |
| A | B55.01103.M003 | 84.06P39.03F | FET MOS SSM6P39TU PC UF6 | R2_SA;HF_SA; | TOSHIBA | SSM6P39TU |  |  | Purchase |  |  |  |  |
| 3 | B55.01103.M003 | 078.10321.02S1 | CHIP CAP C 0.01U 16V K0201 X7R | R2_SA;HF_SA;G_SA; | DARFON;MURATA;TAIYO;WALSIN;YAGEO;SAMSUNG | C0603X7R103KET;GRM033R71C103KE14D;EMK063B7103KP-F;0201B103K160CT;CC0201KRX7R7BB103;CL03B103KO3NNNC | Multiple |  | Purchase | SMT | 72 | PCS | C106 C107 C119 C120 C132 C133 C145 C146 C158 C159 C171 C172 C184 C185 C197 C198 C210 C211 C223 C224 C236 C237 C249 C250 C262 C263 C275 C276 C288 C289 C301 C302 C314 C315 C327 C328 C340 C341 C353 C354 C366 C367 C379 C380 C392 C393 C405 C406 C41 C418 C419 C42 C431 C432 C444 C445 C457 C458 C470 C471 C483 C484 C496 C497 C54 C55 C67 C68 C80 C81 C93 C94 |
| 3 | B55.01103.M003 | 078.10621.0211 | CHIP CAP C 10UF 16V K0805 X7R | R2_SA;HF_SA;G_SA; | SAMSUNG;YAGEO | CL21B106KOQNNNE;CC0805KKX7R7BB106 | Multiple |  | Purchase | SMT | 34 | PCS | C617 C618 C619 C621 C622 C632 C633 C634 C635 C636 C637 C639 C640 C650 C651 C652 C653 C654 C655 C657 C658 C668 C669 C670 C671 C672 C673 C675 C676 C686 C687 C688 C691 C693 |
| 3 | B55.01103.M003 | 078.22612.0201 | CHIP CAP C 22U 25V M1210 X7R T2.8 | R2_SA;HF_SA;G_SA; | MURATA;TAIYO;YAGEO;WALSIN | GRM32ER71E226ME15L;TMK325B7226MM-TR;CC1210MKX7R8BB226;1210B226M250CT | Multiple |  | Purchase | SMT | 4 | PCS | C520 C525 C530 C535 |
| 3 | B55.01103.M003 | 078.22622.M001 | CHIP CAP C 22U 25V K1206 X6S(FACEBOOK) | R2_SA;HF_SA; | MURATA | GRM31CC81E226KE11L | Multiple |  | Purchase | SMT | 13 | PCS | C2 C509 C510 C511 C512 C513 C514 C515 C516 C517 C518 C567 C568 |
| A | B55.01103.M003 | 078.22622.0521 | CHIP CAP C 22U 25V K1206 X5R | R2_SA;HF_SA;G_SA; | YAGEO;SAMSUNG;MURATA;WALSIN;DARFON | CC1206KKX5R8BB226;CL31A226KAHNNNE;GRM31CR61E226KE15L;1206X226K250CT;C3216X5R226KFP |  |  | Purchase |  |  |  |  |
| A | B55.01103.M003 | 078.22622.0821 | CHIP CAP C 22U 25V K1206 X6S | R2_SA;HF_SA; | MURATA;WALSIN | GRM31CC81E226KE11L;1206S226K250CT |  |  | Purchase |  |  |  |  |
| A | B55.01103.M003 | 078.22622.082N | CHIP CAP C 22U 25V K1206 X6S | R2_SA;HF_SA; | MURATA | GRM31CC81E226KE11K |  |  | Purchase |  |  |  |  |
| 3 | B55.01103.M003 | 078.47522.0211 | CHIP CAP C 4.7U 25V K0805 X7R | R2_SA;HF_SA;G_SA; | DARFON;MURATA;SAMSUNG;TAIYO;WALSIN;YAGEO | C2012X7R475KFP;GRM21BR71E475KA73L;CL21B475KAFNNNE;TMK212AB7475KG-T;0805B475K250CT;CC0805KKX7R8BB475 | Multiple |  | Purchase | SMT | 40 | PCS | C100 C112 C126 C138 C151 C164 C179 C192 C204 C217 C230 C242 C255 C268 C282 C294 C307 C321 C334 C347 C360 C373 C386 C399 C412 C424 C437 C450 C464 C477 C49 C490 C503 C61 C624 C642 C660 C678 C74 C87 |
| 3 | B55.01103.M003 | 079.2771D.0011 | CHIP CAP 270UF 16V M 6.3*9.9 SVPG OS-CON | R2_SA;HF_SA; | PANASONIC | 16SVPG270M | Single |  | Purchase | SMT | 6 | PCS | TC1 TC2 TC3 TC4 TC5 TC6 |
| 3 | B55.01103.M003 | 083.00195.0B70 | LED B/Y LTST-C195TBJSKTINV SMD | R2_SA;HF_SA; | LITEON | LTST-C195TBJSKTINV | Multiple |  | Purchase | SMT | 24 | PCS | LED1 LED10 LED11 LED12 LED13 LED14 LED15 LED16 LED17 LED18 LED19 LED2 LED20 LED21 LED22 LED23 LED24 LED3 LED4 LED5 LED6 LED7 LED8 LED9 |
| A | B55.01103.M003 | 83.19223.H70 | LED Y/B 19-223/Y2BHC-C01/2TSM | R2_SA;HF_SA; | EVERLIGHT | 19-223/Y2BHC-C01/2T |  |  | Purchase |  |  |  |  |
| 3 | B55.01103.M003 | 083.04040.0070 | LED IR EMITT AA4040F3S SMD | R2_SA;HF_SA; | KINGBRIGHT | AA4040F3S | Multiple |  | Purchase | SMT | 1 | PCS | LED25 |
| A | B55.01103.M003 | 083.04256.0070 | LED IR SFH4256 SMD | R2_SA;HF_SA; | OSRAM | SFH4256 |  |  | Purchase |  |  |  |  |
| 3 | B55.01103.M003 | 084.08201.0037 | FET MOS IRFH8201TRPBF PQFN 5X6 8P | R2_SA;HF_SA; | IR | IRFH8201TRPBF | Multiple |  | Purchase | SMT | 9 | PCS | Q194 Q195 Q196 Q197 Q198 Q199 Q201 Q202 Q203 |
| A | B55.01103.M003 | 084.00925.003N | FET MOS PH0925CL,115 NC LFPAK 4P | R2_SA;HF_SA; | NXP | PH0925CL,115 |  |  | Purchase |  |  |  |  |
| 3 | B55.01103.M003 | 084.3K324.0031 | FET MOS NC SSM3K324R SOT-23F 3P | R2_SA;HF_SA; | TOSHIBA | SSM3K324R | Multiple |  | Purchase | SMT | 27 | PCS | Q17 Q243 Q244 Q245 Q246 Q247 Q248 Q249 Q250 Q251 Q252 Q253 Q254 Q255 Q256 Q257 Q258 Q259 Q260 Q261 Q262 Q263 Q264 Q265 Q266 Q29 Q33 |
| A | B55.01103.M003 | 084.06244.0031 | FET MOS IRLML6244TRPBF SOT-23 | R2_SA;HF_SA; | IR | IRLML6244TRPBF |  |  | Purchase |  |  |  |  |
| 3 | B55.01103.M003 | 63.00000.00L | CHIP RES 0 J 1/10W 0603 | R2_SA;HF_SA;G_SA; | TA-I ; RALEC ; YAGEO ; WALSIN | RM06JTN0 ; RTT03000JTP ; RC0603JR-070RL ; WR06X000PTL | Multiple |  | Purchase | SMT | 4 | PCS | R1101 R1120 R1139 R1158 |
| 3 | B55.01103.M003 | 63.10234.1DL | CHIP RES 1K J 1/16W 0402 | R2_SA;HF_SA;G_SA; | TA-I;RALEC;CYNTEC;YAGEO;WALSIN | RM04JTN102 ; RTT02102JTH ; RR0510S-102-JN ; RC0402JR-071KL;WR04X102JTL | Multiple |  | Purchase | SMT | 14 | PCS | R10 R1021 R1055 R1068 R1069 R11 R12 R1294 R1295 R13 R417 R418 R444 R447 |
| 3 | B55.01103.M003 | 63.10334.L0L | CHIP RES 10K J 1/16W 0402 13" REEL | R2_SA;HF_SA;G_SA; | YAGEO;RALEC;WALSIN;TAI | RC0402JR-1310KL;RTT02103JH5;WR04X103 JHL;RM04JLN103 | Multiple |  | Purchase | SMT | 1 | PCS | R1004 |
| 3 | B55.01103.M003 | 63.27131.16L | CHIP RES 270 J 1/8W 0805(ROHS) | R2_SA;HF_SA;G_SA; | TAI;RALEC;YAGEO | RM10JTN271;RTT05271JTP;RC0805JR-07270RL | Multiple |  | Purchase | SMT | 4 | PCS | R965 R970 R975 R980 |
| 3 | B55.01103.M003 | 63.33334.1DL | CHIP RES 33K J 1/16W 0402 | R2_SA;HF_SA;G_SA; | TA-I;RALEC;CYNTEC;YAGEO;WALSIN | RM04JTN333;RTT02333JTH;RR0510S-333-JN;RC0402JR-0733KL;WR04X333JTL | Multiple |  | Purchase | SMT | 1 | PCS | R1177 |
| 3 | B55.01103.M003 | 63.47233.15L | CHIP RES 4.7K J 1/10W 0603 | R2_SA;HF_SA;G_SA; | TA-I ; RALEC ; YAGEO ; WALSIN | RM06JTN472 ; RTT03472JTP ; RC0603JR-074K7L ; WR06X472 JTL | Multiple |  | Purchase | SMT | 1 | PCS | R1062 |
| 3 | B55.01103.M003 | 63.47234.1DL | CHIP RES 4.7K J 1/16W 0402 | R2_SA;HF_SA;G_SA; | TA-I;RALEC;CYNTEC;YAGEO;WALSIN | RM04JTN472 ; RTT02472JTH ; RR0510S-472-JN ; RC0402JR-074K7L;WR04X472JTL | Multiple |  | Purchase | SMT | 76 | PCS | R179 R184 R195 R200 R211 R216 R227 R232 R243 R248 R259 R264 R275 R280 R291 R296 R307 R312 R323 R328 R339 R344 R355 R360 R376 R383 R399 R406 R422 R429 R445 R452 R468 R475 R491 R498 R514 R521 R537 R544 R560 R567 R583 R590 R606 R613 R629 R636 R652 R659 R675 R682 R698 R705 R721 R728 R744 R751 R767 R774 R790 R796 R813 R819 R836 R842 R859 R867 R882 R889 R905 R912 R963 R966 R968 R971 |
| 3 | B55.01103.M003 | 63.68031.16L | CHIP RES 68 J 1/8W 0805 | R2_SA;HF_SA;G_SA; | RALEC ; TA-I ; YAGEO | RTT05680JTP ; RM10JTN680 ; RC0805JR-0768RL | Multiple |  | Purchase | SMT | 1 | PCS | R1065 |
| 3 | B55.01103.M003 | 63.R0031.16L | CHIP RES 0 J 1/8W 0805 | R2_SA;HF_SA;G_SA; | TAI;RALEC;YAGEO;WALSIN | RM10JTN0 ; RTT05000JTP ; RC0805JR-070RL ; WR08X000PTL | Multiple |  | Purchase | SMT | 4 | PCS | R1022 R1056 R152 R153 |
| 3 | B55.01103.M003 | 63.R0032.11L | CHIP RES 0 J 1/4W 1206 (ROHS) | R2_SA;HF_SA;G_SA; | TA-I ; RALEC ; YAGEO; WALSIN | RM12JTN0 ; RTT06000JTP ; RC1206JR-070RL; WR12X000 PTL | Multiple |  | Purchase | SMT | 1 | PCS | R1174 |
| 3 | B55.01103.M003 | 63.R0034.1DL | CHIP RES 0 J 1/16W 0402 | R2_SA;HF_SA;G_SA; | TAI;RALEC;CYNTEC;YAGEO;WALSIN | RM04JTN0;RTT02000JTH;RR0510X-000-XN;RC0402JR-070RL;WR04X000PTL | Multiple |  | Purchase | SMT | 150 | PCS | R1027 R1028 R1029 R1030 R104 R1066 R1067 R1075 R1076 R1078 R1079 R1081 R1082 R1083 R1088 R1089 R109 R1092 R1093 R1094 R1095 R1096 R1099 R110 R1114 R1117 R1129 R1132 R1136 R1149 R1153 R1155 R1167 R117 R1170 R1178 R1179 R118 R1184 R1185 R127 R128 R137 R138 R182 R187 R198 R203 R21 R214 R219 R22 R230 R235 R246 R251 R262 R267 R278 R283 R294 R299 R30 R310 R315 R326 R33 R331 R342 R347 R35 R354 R357 R358 R363 R379 R386 R39 R40 R403 R409 R425 R432 R44 R449 R455 R471 R478 R48 R49 R490 R494 R495 R501 R517 R524 R540 R547 R56 R564 R570 R587 R593 R60 R609 R61 R616 R633 R639 R656 R66 R662 R67 R679 R685 R701 R708 R725 R731 R748 R75 R754 R76 R771 R777 R793 R800 R816 R823 R839 R846 R862 R869 R87 R88 R885 R892 R908 R915 R919 R925 R935 R946 R95 R955 R986 R987 R988 R992 RR985 |
| 3 | B55.01103.M003 | 64.10006.6DL | CHIP RES 100 D 1/16W 0402 | R2_SA;HF_SA;G_SA; | RALEC;TAI;CYNTEC;YAGEO | RTT021000DTH;RM04DTN1000;RR0510P-101-DN;RC0402DR-07100RL | Multiple |  | Purchase | SMT | 4 | PCS | R1024 R1025 R982 R983 |
| 3 | B55.01103.M003 | 64.10015.16L | CHIP RES 1K F 1/8W 0805(ROHS) | R2_SA;HF_SA;G_SA; | YAGEO;RALEC;TAI | RC0805FR-071KL;RTT051001FTP;RM10FTN1001 | Multiple |  | Purchase | SMT | 4 | PCS | R962 R967 R972 R977 |
| 3 | B55.01103.M003 | 64.10015.6DL | CHIP RES 1K F 1/16W 0402 | R2_SA;HF_SA;G_SA; | TA-I;RALEC;CYNTEC;YAGEO;WALSIN | RM04FTN1001 ; RTT021001FTH ; RR0510S-102-FN ; RC0402FR-071KL;WR04X1001FTL | Multiple |  | Purchase | SMT | 4 | PCS | R142 R16 R8 R9 |
| 3 | B55.01103.M003 | 64.10025.6DL | CHIP RES 10K F 1/16W 0402 | R2_SA;HF_SA;G_SA; | TA-I;RALEC;CYNTEC;YAGEO;WALSIN | RM04FTN1002 ; RTT021002FTH ; RR0510S-103-FN ; RC0402FR-0710KL;WR04X1002FTL | Multiple |  | Purchase | SMT | 80 | PCS | R1 R1037 R1063 R1102 R1113 R1121 R1130 R114 R1140 R1150 R1159 R116 R1171 R1175 R1180 R132 R165 R167 R169 R174 R191 R207 R223 R239 R255 R271 R287 R303 R319 R335 R351 R369 R371 R392 R4 R401 R415 R438 R440 R441 R461 R484 R493 R497 R5 R502 R503 R504 R505 R507 R509 R530 R553 R576 R599 R6 R622 R645 R668 R691 R7 R714 R737 R760 R783 R806 R829 R852 R875 R898 R926 R931 R937 R941 R947 R951 R957 R961 R989 R997 |
| 3 | B55.01103.M003 | 64.10035.6DL | CHIP RES 100K F 1/16W 0402 | R2_SA;HF_SA;G_SA; | TA-I;RALEC;CYNTEC;YAGEO;WALSIN | RM04FTN1003 ; RTT021003FTH ; RR0510S-104-FN ; RC0402FR-07100KL;WR04X1003FTL | Multiple |  | Purchase | SMT | 24 | PCS | R1003 R1005 R1007 R102 R103 R1036 R1041 R1043 R1045 R1064 R115 R158 R161 R3 R928 R930 R932 R933 R944 R954 R96 R97 R98 R995 |
| 3 | B55.01103.M003 | 64.10R05.16L | CHIP RES 10 F 1/8W 0805(ROHS) | R2_SA;HF_SA;G_SA; | TAI;YAGEO;RALEC | RM10FTN10R0;RC0805FR-0710RL;RTT0510R0FTP | Multiple |  | Purchase | SMT | 9 | PCS | R1015 R1016 R1017 R1018 R1019 R1020 R1052 R1053 R1054 |
| 3 | B55.01103.M003 | 64.10R05.55L | CHIP RES 10 F 1/10W 0603 | R2_SA;HF_SA;G_SA; | TA-I;RALEC;YAGEO;WALSIN | RM06FTN10R0 ; RTT0310R0FTP ; RC0603FR-0710RL;WR06X10R0FTL | Multiple |  | Purchase | SMT | 5 | PCS | R1106 R1125 R1144 R1163 R1176 |
| 3 | B55.01103.M003 | 64.10R05.6DL | CHIP RES 10 F 1/16W 0402 | R2_SA;HF_SA;G_SA; | TAI;RALEC;CYNTEC;YAGEO;WALSIN | RM04FTN10R0;RTT0210R0FTH;RR0510S-100-FN;RC0402FR-0710RL;WR04X10R0FTL | Multiple |  | Purchase | SMT | 14 | PCS | R1000 R1026 R1032 R1035 R1038 R1058 R1059 R1060 R1061 R1111 R984 R996 R998 R999 |
| 3 | B55.01103.M003 | 64.11025.6DL | CHIP RES 11K F 1/16W 0402 | R2_SA;HF_SA;G_SA; | TA-I ; RALEC ; CYNTEC ; YAGEO;WALSIN | RM04FTN1102 ; RTT021102FTH ; RR0510S-1102-FN ; RC0402FR-0711KL;WR04X1102FTL | Multiple |  | Purchase | SMT | 2 | PCS | R1001 R1039 |
| 3 | B55.01103.M003 | 64.12425.6DL | CHIP RES 12.4K F 1/16W 0402 | R2_SA;HF_SA;G_SA; | TA-I;RALEC;CYNTEC;YAGEO | RM04FTN1242;RTT021242FTH;RR0510S-1242-FN;RC0402FR-0712K4L | Multiple |  | Purchase | SMT | 1 | PCS | R1046 |
| 3 | B55.01103.M003 | 64.13005.55L | CHIP RES 130 F 1/10W 0603 | R2_SA;HF_SA;G_SA; | TA-I ; RALEC ; YAGEO | RM06FTN1300 ; RTT031300FTP ; RC0603FR-07130RL | Multiple |  | Purchase | SMT | 24 | PCS | R205 R220 R236 R253 R268 R284 R300 R316 R332 R348 R364 R375 R382 R390 R402 R410 R411 R412 R428 R434 R436 R448 R456 R459 |
| 3 | B55.01103.M003 | 64.14015.6DL | CHIP RES 1.4K F 1/16W 0402(ROHS) | R2_SA;HF_SA;G_SA; | CYNTEC;RALTEC;TAI;YAGEO | RR0510S-1401-FN;RTT021401FTH;RM04FTN1401;RC0402FR-071K4L | Multiple |  | Purchase | SMT | 1 | PCS | R994 |
| 3 | B55.01103.M003 | 64.14325.6DL | CHIP RES 14.3K F 1/16W 0402 | R2_SA;HF_SA;G_SA; | RALEC ; CYNTEC ; TA-I ; YAGEO | RTT021432FTH ; RR0510S-1432-FN ; RM04FTN1432 ; RC0402FR-0714K3L | Multiple |  | Purchase | SMT | 1 | PCS | R1008 |
| 3 | B55.01103.M003 | 64.14335.L0L | CHIP RES 143K F 1/16W 0402 | R2_SA;HF_SA;G_SA; | TAI;RALEC;CYNTEC | RM04FTN1433;RTT021433FTH;RR0510S-1433-FN | Multiple |  | Purchase | SMT | 4 | PCS | R1110 R1131 R1148 R1168 |
| 3 | B55.01103.M003 | 64.15025.6DL | CHIP RES 15K F 1/16W 0402 | R2_SA;HF_SA;G_SA; | TA-I;RALEC;CYNTEC;YAGEO | RM04FTN1502;RTT021502FTH;RR0510S-153-FN;RC0402FR-0715KL | Multiple |  | Purchase | SMT | 5 | PCS | R1105 R1124 R1142 R1161 R1183 |
| 3 | B55.01103.M003 | 64.16225.6DL | CHIP RES 16.2K F 1/16W 0402 | R2_SA;HF_SA;G_SA; | TAI;YAGEO;CYNTEC;RALEC | RM04FTN1622;RC0402FR-0716K2L;RR0510S-1622-F;RTT021622FTH | Multiple |  | Purchase | SMT | 4 | PCS | R122 R166 R168 R170 |
| 3 | B55.01103.M003 | 64.20015.6DL | CHIP RES 2K F 1/16W 0402 | R2_SA;HF_SA;G_SA; | TA-I;RALEC;CYNTEC;YAGEO;WALSIN | RM04FTN2001 ; RTT022001FTH ; RR0510S-202-FN ; RC0402FR-072KL;WR04X2001FTL | Multiple |  | Purchase | SMT | 1 | PCS | R1181 |
| 3 | B55.01103.M003 | 64.20035.6DL | CHIP RES 200K F 1/16W 0402 | R2_SA;HF_SA;G_SA; | TA-I;RALEC;CYNTEC;YAGEO;WALSIN | RM04FTN2003 ; RTT022003FTH ; RR0510S-204-FN ; RC0402FR-07200KL;WR04X2003FTL | Multiple |  | Purchase | SMT | 45 | PCS | R1107 R1126 R1145 R1164 R144 R145 R146 R147 R186 R189 R202 R218 R234 R250 R266 R282 R298 R314 R330 R346 R362 R385 R408 R431 R454 R477 R500 R523 R546 R569 R592 R615 R638 R661 R684 R707 R730 R753 R776 R799 R822 R845 R868 R891 R914 |
| 3 | B55.01103.M003 | 64.21025.6DL | CHIP RES 21K F 1/16W 0402 | R2_SA;HF_SA;G_SA; | TA-I ; RALEC ; CYNTEC ; YAGEO;WALSIN | RM04FTN2102 ; RTT022102FTH ; RR0510S-2102-FN ; RC0402FR-0721KL;WR04X2102FTL | Multiple |  | Purchase | SMT | 1 | PCS | R1042 |
| 3 | B55.01103.M003 | 64.22005.55L | CHIP RES 220 F 1/10W 0603 | R2_SA;HF_SA;G_SA; | TAI;RALEC;YAGEO;WALSIN | RM06FTN2200;RTT032200FTP;RC0603FR-07220RL;WR06X2200FTL | Multiple |  | Purchase | SMT | 36 | PCS | R176 R193 R209 R225 R241 R257 R273 R289 R305 R321 R337 R353 R373 R396 R419 R442 R465 R488 R511 R534 R557 R580 R603 R626 R649 R672 R695 R718 R741 R764 R787 R810 R833 R856 R879 R902 |
| 3 | B55.01103.M003 | 64.22015.6DL | CHIP RES 2.2K F 1/16W 0402 | R2_SA;HF_SA;G_SA; | TA-I;RALEC;CYNTEC;YAGEO | RM04FTN2201;RTT022201FTH;RR0510S-222-FN;RC0402FR-072K2L | Multiple |  | Purchase | SMT | 4 | PCS | R601 R602 R604 R605 |
| 3 | B55.01103.M003 | 64.27015.6DL | CHIP RES 2.7K F 1/16W 0402 | R2_SA;HF_SA;G_SA; | TAI;RALEC;CYNTEC;YAGEO | RM04FTN2701;RTT022701FTH;RR0510S-2701-FN;RC0402FR-072K7L | Multiple |  | Purchase | SMT | 4 | PCS | R1103 R1122 R1141 R1160 |
| 3 | B55.01103.M003 | 64.27025.55L | CHIP RES 27K F 1/10W 0603 | R2_SA;HF_SA;G_SA; | TA-I ; RALEC ; YAGEO | RM06FTN2702 ; RTT032702FTP ; RC0603FR-0727KL | Multiple |  | Purchase | SMT | 8 | PCS | R924 R929 R936 R940 R945 R950 R956 R960 |
| 3 | B55.01103.M003 | 64.2R005.81L | CHIP RES 2 F 1/2W 1206 | R2_SA;HF_SA;G_SA; | TAI;YAGEO;CYNTEC | RMH12FT2R00;RC1206FR-7W2RL;RL1632H-2R0-FN | Multiple |  | Purchase | SMT | 72 | PCS | R175 R177 R190 R192 R206 R208 R222 R224 R238 R240 R254 R256 R270 R272 R286 R288 R302 R304 R318 R320 R334 R336 R350 R352 R368 R370 R391 R393 R414 R416 R437 R439 R460 R462 R483 R485 R506 R508 R529 R531 R552 R554 R575 R577 R598 R600 R621 R623 R644 R646 R667 R669 R690 R692 R713 R715 R736 R738 R759 R761 R782 R784 R805 R807 R828 R830 R851 R853 R874 R876 R897 R899 |
| 3 | B55.01103.M003 | 64.2R205.55L | CHIP RES 2.2 F 1/10W 0603 | R2_SA;HF_SA;G_SA; | TAI;YAGEO;RALEC;WALSIN | RM06FTN2R20;RC0603FR-072R2L;RTT032R20FTP;WR06W2R20FTL | Multiple |  | Purchase | SMT | 5 | PCS | R1098 R1118 R1137 R1156 R1173 |
| 3 | B55.01103.M003 | 64.30035.6DL | CHIP RES 300K F 1/16W 0402 | R2_SA;HF_SA;G_SA; | TAI;RALEC;CYNTEC;YAGEO;WALSIN | RM04FTN3003;RTT023003FTH;RR0510S-304-FN;RC0402FR-07300KL;WR04X3003FTL | Multiple |  | Purchase | SMT | 40 | PCS | R148 R149 R150 R151 R185 R201 R217 R233 R249 R265 R281 R297 R313 R329 R345 R361 R384 R407 R430 R453 R476 R499 R522 R545 R568 R591 R614 R637 R660 R683 R706 R729 R752 R775 R797 R820 R843 R865 R890 R913 |
| 3 | B55.01103.M003 | 64.30935.6DL | CHIP RES 309K F 1/16W 0402 | R2_SA;HF_SA;G_SA; | TA-I;RALEC;CYNTEC;YAGEO | RM04FTN3093;RTT023093FTH;RR0510S-3093-FN;RC0402FR-07309KL | Multiple |  | Purchase | SMT | 4 | PCS | R1112 R1133 R1151 R1169 |
| 3 | B55.01103.M003 | 64.33015.55L | CHIP RES 3.3K F 1/10W 0603(ROH | R2_SA;HF_SA;G_SA; | TAI;RALEC;YAGEO | RM06FTN3301;RTT033301FTP;RC0603FR-073K3L | Multiple |  | Purchase | SMT | 1 | PCS | R1293 |
| 3 | B55.01103.M003 | 64.38315.6DL | CHIP RES 3.83K F 1/16W 0402 | R2_SA;HF_SA;G_SA; | TA-I;RALEC;CYNTEC;YAGEO | RM04FTN3831;RTT023831FTH;RR0510S-3831-FN;RC0402FR-073K83L | Multiple |  | Purchase | SMT | 3 | PCS | R1002 R1040 R2 |
| 3 | B55.01103.M003 | 64.39215.6DL | CHIP RES 3.92K F 1/16W 0402 | R2_SA;HF_SA;G_SA; | RALEC ; CYNTEC ; TA-I ; YAGEO | RTT023921FTH ; RR0510S-3921-FN ; RM04FTN3921 ; RC0402FR-073K92L | Multiple |  | Purchase | SMT | 2 | PCS | R1013 R1050 |
| 3 | B55.01103.M003 | 64.47015.6DL | CHIP RES 4.7K F 1/16W 0402 | R2_SA;HF_SA;G_SA; | TA-I;RALEC;CYNTEC;YAGEO;WALSIN | RM04FTN4701;RTT024701FTH;RR0510S-472-FN;RC0402FR-074K7L;WR04X4701FTL | Multiple |  | Purchase | SMT | 160 | PCS | R106 R1073 R1074 R108 R1086 R1087 R112 R121 R125 R126 R129 R1297 R1298 R1299 R1300 R1301 R1302 R1303 R1304 R1305 R1306 R1307 R1308 R136 R139 R140 R154 R155 R156 R157 R160 R162 R164 R171 R172 R173 R178 R18 R181 R183 R188 R19 R194 R197 R199 R20 R210 R213 R215 R226 R229 R23 R231 R242 R245 R247 R258 R26 R261 R263 R27 R274 R277 R279 R29 R290 R293 R295 R306 R309 R31 R311 R322 R325 R327 R338 R341 R343 R359 R365 R366 R372 R374 R378 R38 R381 R388 R389 R394 R395 R398 R404 R41 R42 R427 R451 R466 R467 R470 R472 R473 R474 R479 R480 R481 R482 R486 R487 R489 R496 R50 R51 R519 R52 R53 R542 R55 R565 R58 R589 R611 R62 R63 R635 R657 R680 R69 R70 R703 R71 R72 R727 R74 R750 R773 R79 R795 R81 R818 R83 R84 R841 R86 R864 R887 R89 R90 R91 R910 R92 R922 R927 R93 R934 R938 R94 R942 R948 R953 R958 |
| 3 | B55.01103.M003 | 64.49915.6DL | CHIP RES 4.99K F 1/16W 0402 | R2_SA;HF_SA;G_SA; | TA-I;RALEC;CYNTEC;YAGEO;WALSIN | RM04FTN4991 ; RTT024991FTH ; RR0510S-4991-FN ; RC0402FR-074K99L ; WR04X4991FTL | Multiple |  | Purchase | SMT | 2 | PCS | R1014 R1051 |
| 3 | B55.01103.M003 | 64.49925.6DL | CHIP RES 49.9K F 1/16W 0402 | R2_SA;HF_SA;G_SA; | TA-I ; RALEC ; CYNTEC ; YAGEO ; WALSIN | RM04FTN4992 ; RTT024992FTH ; RR0510S-4992-FN ; RC0402FR-0749K9L ; WR04X4992FTL | Multiple |  | Purchase | SMT | 4 | PCS | R1010 R1011 R1048 R1049 |
| 3 | B55.01103.M003 | 64.73215.6DL | CHIP RES 7.32K F 1/16W 0402 | R2_SA;HF_SA;G_SA; | TA-I;RALEC;CYNTEC;YAGEO;WALSIN | RM04FTN7321;RTT027321FTH;RR0510S-7321-FN;RC0402FR-077K32L;WR04X7321FTL | Multiple |  | Purchase | SMT | 1 | PCS | R133 |
| 3 | B55.01103.M003 | 64.75025.6DL | CHIP RES 75K F 1/16W 0402 | R2_SA;HF_SA;G_SA; | TA-I;RALEC;CYNTEC;YAGEO;WALSIN | RM04FTN7502;RTT027502FTH;RR0510S-753-FN;RC0402FR-0775KL;WR04X7502FTL | Multiple |  | Purchase | SMT | 1 | PCS | R1044 |
| 3 | B55.01103.M003 | 64.91R05.55L | CHIP RES 91 F 1/10W 0603 | R2_SA;HF_SA;G_SA; | TA-I ; RALEC ; YAGEO | RM06FTN91R0 ; RTT0391R0FTP ; RC0603FR-0791RL | Multiple |  | Purchase | SMT | 24 | PCS | R204 R221 R237 R252 R269 R285 R301 R317 R333 R349 R367 R380 R387 R397 R405 R413 R421 R426 R433 R435 R443 R450 R457 R458 |
| 3 | B55.01103.M003 | 68.00084.831 | CHIP BEAD BLM21PG220SN1D (LF) | R2_SA;HF_SA; | MURATA | BLM21PG220SN1D | Multiple |  | Purchase | SMT | 4 | PCS | L1 L3 L5 L7 |
| A | B55.01103.M003 | 68.00216.081 | CHIP BEAD HCB2012KF-220T60 | R2_SA;HF_SA; | TAITECH | HCB2012KF-220T60 |  |  | Purchase |  |  |  |  |
| 3 | B55.01103.M003 | 68.1R010.20K | CHIP CHOKE 1.0UH PCMB103T-1R0MS | R2_SA;HF_SA;G_SA; | CYNTEC | PCMB103T-1R0MS | Multiple |  | Purchase | SMT | 4 | PCS | L2 L4 L6 L8 |
| A | B55.01103.M003 | 68.1R01E.10H | CHIP IND 1.0UH M MMD-10CZ-1R0M-X2W | R2_SA;HF_SA; | MAGLAYER | MMD-10CZ-1R0M-X2W |  |  | Purchase |  |  |  |  |
| 3 | B55.01103.M003 | 68.4R71A.20H | CHIP CHOKE 4.7UH PCMB063T-4R7MS | R2_SA;HF_SA; | CYNTEC | PCMB063T-4R7MS | Multiple |  | Purchase | SMT | 1 | PCS | L9 |
| A | B55.01103.M003 | 68.4R71C.10U | CHIP IND 4.7UH SPM6530T-4R7M | R2_SA;HF_SA; | TDK | SPM6530T-4R7M |  |  | Purchase |  |  |  |  |
| 3 | B55.01103.M003 | 71.09557.D0W | IC I2C/SMBUS PCA9557PWR TSSOP 16P | R2_SA;HF_SA; | TI | PCA9557PWR | Multiple |  | Purchase | SMT | 1 | PCS | U10 |
| A | B55.01103.M003 | 071.09557.000W | IC IC2/SMBUS PCA9557PW,118 TSSOP 16P | R2_SA;HF_SA; | NXP | PCA9557PW,118 |  |  | Purchase |  |  |  |  |
| 3 | B55.01103.M003 | 71.P9511.00W | IC BUF PCA9511ADP-T TSSOP 8P | R2_SA;HF_SA; | NXP | PCA9511ADP-T | Single |  | Purchase | SMT | 2 | PCS | U23 U24 |
| 3 | B55.01103.M003 | 72.24C64.K01 | IC EEPROM M24C64-RMN6TP SOIC 8P | R2_SA;HF_SA; | STMICROELECTRONICS INC | M24C64-RMN6TP | Multiple |  | Purchase | SMT | 1 | PCS | U13 |
| A | B55.01103.M003 | 072.02464.0A01 | IC EEPROM FM24C64D-SO-T-G SOP 8P | R2_SA;HF_SA; | FUDAN | FM24C64D-SO-T-G |  |  | Purchase |  |  |  |  |
| 3 | B55.01103.M003 | 73.01G08.L03 | IC CMOS SN74LVC1G08DCKR SC-70 | R2_SA;HF_SA;G_SA; | TI | SN74LVC1G08DCKR | Multiple |  | Purchase | SMT | 5 | PCS | U1 U49 U50 U51 U52 |
| A | B55.01103.M003 | 073.7SZ08.000G | IC CMOS TC7SZ08FU,LJ(CT SSOP5-P-0.65A | R2_SA;HF_SA; | TOSHIBA | TC7SZ08FU,LJ(CT |  |  | Purchase |  |  |  |  |
| 3 | B55.01103.M003 | 73.01G32.A0H | IC CMOS SN74LVC1G32DCKR SC70-5 | R2_SA;HF_SA; | TI | SN74LVC1G32DCKR | Multiple |  | Purchase | SMT | 1 | PCS | U2 |
| A | B55.01103.M003 | 73.01G32.AHH | IC CMOS 74LVC1G32GW,125 SC70-5 | R2_SA;HF_SA;G_SA; | NXP | 74LVC1G32GW,125 |  |  | Purchase |  |  |  |  |
| A | B55.01103.M003 | 73.7SZ32.AAH | IC CMOS NC7SZ32P5X_NL SC70-5 | R2_SA;HF_SA;G_SA; | FAIRCHILD | NC7SZ32P5X_NL |  |  | Purchase |  |  |  |  |
| 3 | B55.01103.M003 | 73.03245.F0B | IC BUS SW SN74CBTLV3245APWR TSSOP 20P | R2_SA;HF_SA; | TI | SN74CBTLV3245APWR | Multiple |  | Purchase | SMT | 2 | PCS | U17 U18 |
| A | B55.01103.M003 | 73.33245.00B | IC BUS SW PI3B3245LE TSSOP 20P | R2_SA;HF_SA; | PERICOM | PI3B3245LE |  |  | Purchase |  |  |  |  |
| 3 | B55.01103.M003 | 73.07407.BHB | IC CMOS SN74LV07APWR TSSOP 14P | R2_SA;HF_SA; | TI | SN74LV07APWR | Multiple |  | Purchase | SMT | 1 | PCS | U11 |
| A | B55.01103.M003 | 073.07407.0A0B | IC CMOS 74LCX07FT(AE) TSSOP 14P | R2_SA;HF_SA; | TOSHIBA | 74LCX07FT(AE) |  |  | Purchase |  |  |  |  |
| A | B55.01103.M003 | 73.07407.DHB | IC CMOS 74LVC07APW TSSOP 14P | R2_SA;HF_SA; | NXP | 74LVC07APW |  |  | Purchase |  |  |  |  |
| 3 | B55.01103.M003 | 74.00075.B79 | IC TEMP SENSOR TMP75AIDGKR MSOP 8P | R2_SA;HF_SA; | TI | TMP75AIDGKR | Multiple |  | Purchase | SMT | 2 | PCS | U15 U16 |
| A | B55.01103.M003 | 074.00752.M001 | IC TEMP SEN STTS75DS2F MSOP 8P(FIONA) | R2_SA;HF_SA; | ST | STTS75DS2F |  |  | Purchase |  |  |  |  |
| 3 | B55.01103.M003 | 74.07368.071 | IC PWM COMPARATOR NCT7368S SOP 8P | R2_SA;HF_SA; | NUVOTON | NCT7368S | Single |  | Purchase | SMT | 2 | PCS | U12 U20 |
| 3 | B55.01103.M003 | 74.53312.073 | IC PWM CTRL TPS53312RGTR QFN 16P | R2_SA;HF_SA; | TI | TPS53312RGTR | Single |  | Purchase | SMT | 1 | PCS | U35 |
| 3 | B55.01103.M003 | 74.53319.073 | IC PWR CTRL TPS53319DQPR QFN 22P | R2_SA;HF_SA; | TI | TPS53319DQPR | Single |  | Purchase | SMT | 4 | PCS | U31 U32 U33 U34 |
| 3 | B55.01103.M003 | 77.21071.02L | CHIP CAP POS 100U 16V M7343 ESR | R2_SA;HF_SA; | PANASONIC | 16TQC100MYF | Single |  | Purchase | SMT | 1 | PCS | TC15 |
| 3 | B55.01103.M003 | 77.22271.L03 | CHIP CAP POS 220U 10V M7343 | R2_SA;HF_SA; | PANASONIC | 10TPE220ML | Single |  | Purchase | SMT | 8 | PCS | TC10 TC11 TC12 TC13 TC14 TC7 TC8 TC9 |
| 3 | B55.01103.M003 | 78.10134.1FL | CHIP CAP C 100P 50V J0402 NPO | R2_SA;HF_SA;G_SA; | AVX;DARFON;MURATA;PHYCOMP;SAMSUNG;TAIYO;WALSIN;YAGEO | CM05CG101J50AH;C1005NP0101JGT;GRM1555C1H101JA01D;223886915101;CL05C101JB5NNNC;UMK105CH101JV-F;0402N101J500CT;CC0402JRNPO9BN101 | Multiple |  | Purchase | SMT | 1 | PCS | C692 |
| 3 | B55.01103.M003 | 78.10224.2FL | CHIP CAP C 1000P 50V K0402 X7R | R2_SA;R_SA;HF_SA;G_SA; | AVX;DARFON;MURATA;PHYCOMP;SAMSUNG;TAIYO;MURATA;AVX;YAGEO | CM05X7R102K50AH;C1005X7R102KGT;GRM155R71H102KA01D;223858715623;CL05B102KB5NNNC;UMK105B7102KV-F;WBM155R71H102KA01D;04025C102KAT2A;CC0402KRX7R9BB102 | Multiple |  | Purchase | SMT | 3 | PCS | C539 C553 C699 |
| 3 | B55.01103.M003 | 78.10324.2FL | CHIP CAP C 0.01U 50V K0402 X7R | R2_SA;HF_SA;G_SA; | MURATA;PHYCOMP;DARFON;SAMSUNG;WALSIN;MURATA;YAGEO | GRM155R71H103KA88D;223858715636;C1005X7R103KGT;CL05B103KB5NNNC;0402B103K500CT;WBM155R71H103KA01D;CC0402KRX7R9BB103 | Multiple |  | Purchase | SMT | 36 | PCS | C102 C115 C123 C141 C154 C167 C176 C188 C205 C218 C232 C245 C258 C269 C281 C297 C310 C318 C335 C349 C362 C375 C388 C400 C414 C427 C43 C440 C453 C461 C474 C492 C505 C63 C75 C89 |
| 3 | B55.01103.M003 | 78.10421.2FL | CHIP CAP C 0.1U 16V K0402 X7R | R2_SA;HF_SA;G_SA; | DARFON;MURATA;PHYCOMP;SAMSUNG;TAIYO;WALSIN;YAGEO | C1005X7R104KET;GRM155R71C104KA88D;223878715649;CL05B104KO5NNNC;EMK105B7104KV-F;0402B104K160CT;CC0402KRX7R7BB104 | Multiple |  | Purchase | SMT | 46 | PCS | C10 C105 C12 C14 C16 C18 C19 C21 C23 C25 C26 C27 C28 C30 C32 C39 C4 C40 C53 C542 C556 C58 C6 C615 C616 C620 C625 C631 C638 C643 C649 C656 C66 C661 C674 C679 C690 C700 C708 C709 C710 C711 C712 C713 C72 C8 |
| 3 | B55.01103.M003 | 78.10422.2BL | CHIP CAP C 0.1U 25V K0603 X7R | R2_SA;HF_SA;G_SA; | AVX;DARFON;MURATA;PHYCOMP;SAMSUNG;TAIYO;WALSIN;YAGEO | 06033C104KAT2A;C1608X7R104KFT;GRM188R71E104KA01D;223891615649;CL10B104KA8NNNC;TMK107B7104KA-T;0603B104K250CT;CC0603KRX7R8BB104 | Multiple |  | Purchase | SMT | 1 | PCS | C698 |
| 3 | B55.01103.M003 | 78.10422.2FL | CHIP CAP C 0.1U 25V K0402 X7R | R2_SA;HF_SA;G_SA; | YAGEO;WALSIN;MURATA;SAMSUNG;TAIYO;DARFON | CC0402KRX7R8BB104;0402B104K250CT;GRM155R71E104KE14D;CL05B104KA5NNNC;TMK105B7104KV-FR;C1005X7R104KFT | Multiple |  | Purchase | SMT | 12 | PCS | C521 C526 C532 C536 C545 C546 C548 C549 C559 C560 C561 C563 |
| 3 | B55.01103.M003 | 78.10424.2BL | CHIP CAP C 0.1U 50V K0603 X7R | R2_SA;HF_SA;G_SA; | MURATA;AVX;PHYCOMP;SAMSUNG;DARFON;WALSIN;YAGEO | GRM188R71H104KA93D;06035C104KAT2A;223858615649;CL10B104KB8NNNC;C1608X7R104KGT;0603B104K500CT;CC0603KRX7R9BB104 | Multiple |  | Purchase | SMT | 4 | PCS | C627 C646 C664 C680 |
| 3 | B55.01103.M003 | 78.10521.2BL | CHIP CAP C 1U 16V K0603 X7R | R2_SA;HF_SA;G_SA; | KEMET;MURATA;TAIYO;TDK;YAGEO;WALSIN;SAMSUNG;DARFON | C0603C105K4RAC;GRM188R71C105KA12D;EMK107B7105KA-T;C1608X7R1C105KT;CC0603KRX7R7BB105;0603B105K160CT;CL10B105KO8NNNC;C1608X7R105KET | Multiple |  | Purchase | SMT | 67 | PCS | C108 C11 C121 C13 C134 C147 C15 C160 C17 C173 C186 C199 C20 C212 C22 C225 C238 C24 C251 C264 C277 C29 C290 C3 C303 C31 C316 C329 C33 C34 C342 C355 C368 C37 C38 C381 C394 C407 C420 C433 C44 C446 C459 C472 C485 C498 C5 C547 C550 C551 C56 C562 C564 C565 C59 C628 C645 C663 C681 C689 C69 C696 C7 C79 C82 C9 C95 |
| 3 | B55.01103.M003 | 78.10522.2BL | CHIP CAP C 1U 25V K0603 X7R | R2_SA;HF_SA;G_SA; | MURATA;TAIYO;WALSIN;SAMSUNG;DARFON;YAGEO | GRM188R71E105KA12D;TMK107B7105KA-T;0603B105K250CT;CL10B105KA8NNNC;C1608X7R105KFT;CC0603KRX7R8BB105 | Multiple |  | Purchase | SMT | 43 | PCS | C101 C114 C128 C140 C153 C166 C180 C193 C206 C219 C231 C243 C256 C271 C284 C296 C309 C323 C336 C348 C361 C374 C387 C401 C413 C426 C439 C452 C466 C479 C491 C50 C504 C522 C527 C531 C537 C541 C555 C62 C694 C76 C88 |
| 3 | B55.01103.M003 | 78.10620.21L | CHIP CAP C 10U 6.3V K0805 X7R | R2_SA;HF_SA;G_SA; | MURATA;TAIYO;DARFON;KYOCERA | GRM21BR70J106KE76L;JMK212B7106KG-T;C2012X7R106KC;CM21X7R106K06AT | Multiple |  | Purchase | SMT | 6 | PCS | C701 C702 C703 C704 C705 C706 |
| 3 | B55.01103.M003 | 78.10621.22L | CHIP CAP C 10U 16V K1206 X7R | R2_SA;HF_SA;G_SA; | MURATA;TDK;AVX;DARFON;SAMSUNG;TAIYO;WALSIN | GRM31CR71C106KA12L;C3216X7R1C106KT;CM316X7R106K16AT;C3216X7R106KEP;CL31B106KOHNNNE;EMK316B7106KL-T;1206B106K160CT | Multiple |  | Purchase | SMT | 36 | PCS | C109 C122 C135 C148 C161 C174 C187 C200 C213 C226 C239 C252 C265 C278 C291 C304 C317 C330 C343 C356 C369 C382 C395 C408 C421 C434 C447 C45 C460 C473 C486 C499 C57 C70 C83 C96 |
| 3 | B55.01103.M003 | 78.15322.2FL | CHIP CAP C 0.015U 25V K0402 X7R | R2_SA;HF_SA;G_SA; | MURATA;TDK;WALSIN;DARFON;PHYCOMP | GRM155R71E153KA61D;C1005X7R1E153KT000F;0402B153K250CT;C1005X7R153KFT;223891715638 | Multiple |  | Purchase | SMT | 2 | PCS | C543 C557 |
| 3 | B55.01103.M003 | 78.22421.2FL | CHIP CAP C 0.22U 16V K0402 X7R | R2_SA;HF_SA;G_SA; | MURATA;SAMSUNG;DARFON;TAIYO;WALSIN;YAGEO | GRM155R71C224KA12D;CL05B224KO5NNNC;C1005X7R224KET;EMK105B7224KV-FR;0402B224K160CT;CC0402KRX7R7BB224 | Multiple |  | Purchase | SMT | 2 | PCS | C540 C554 |
| 3 | B55.01103.M003 | 78.33224.2FL | CHIP CAP C 3300P 50V K0402 X7R | R2_SA;HF_SA;G_SA; | MURATA;AVX;TAIYO;PHYCOMP;DARFON;WALSIN;YAGEO | GRM155R71H332KA01D;04025C332KAT2A;UMK105B7332KV-F;223858715629;C1005X7R332KGT;0402B332K500CT;CC0402KRX7R9BB332 | Multiple |  | Purchase | SMT | 1 | PCS | C695 |
| 3 | B55.01103.M003 | 78.33322.2FL | CHIP CAP C 0.033U 25V K0402 X7 | R2_SA;HF_SA;G_SA; | MURATA;TDK;KEMET;WALSIN;PHYCOMP;YAGEO | GRM155R71E333KA88D;C1005X7R1E333KT000F;C0402C333K3RACTU;0402B333K250CT;223891715643;CC0402KRX7R8BB333 | Multiple |  | Purchase | SMT | 76 | PCS | C103 C104 C116 C117 C129 C130 C142 C143 C155 C156 C168 C169 C181 C182 C194 C195 C207 C208 C220 C221 C233 C234 C246 C247 C259 C260 C272 C273 C285 C286 C298 C299 C311 C312 C324 C325 C337 C338 C350 C351 C363 C364 C365 C376 C377 C378 C389 C390 C391 C402 C403 C404 C415 C416 C428 C429 C441 C442 C454 C455 C467 C468 C480 C481 C493 C494 C506 C507 C51 C52 C64 C65 C77 C78 C90 C91 |
| 3 | B55.01103.M003 | 78.33324.2BL | CHIP CAP 0.033U 50V K0603 X7R | R2_SA;HF_SA;G_SA; | MURATA;AVX;PHYCOMP;DARFON;YAGEO | GRM188R71H333KA61D;06035C333KAT2A;223858615643;C1608X7R333KGT;CC0603KRX7R9BB333 | Multiple |  | Purchase | SMT | 2 | PCS | C552 C566 |
| 3 | B55.01103.M003 | 78.47124.2FL | CHIP CAP C 470P  50V K0402 X7R | R2_SA;HF_SA;G_SA; | AVX;DARFON;MURATA;PHYCOMP;TAIYO;SAMSUNG;WALSIN;YAGEO | 04025C471KAT2A;C1005X7R471KGT;GRM155R71H471KA01D;223858715618;UMK105B7471KV-F;CL05B471KB5NNNC;0402B471K500CT;CC0402KRX7R9BB471 | Multiple |  | Purchase | SMT | 4 | PCS | C629 C647 C665 C683 |
| 3 | B55.01103.M003 | 83.00016.A1H | DIODE SW BAS16H,115 100VSOD123F | R2_SA;HF_SA;G_SA; | NEXPERIA | BAS16H,115 | Multiple |  | Purchase | SMT | 8 | PCS | D37 D38 D39 D40 D41 D42 D43 D44 |
| A | B55.01103.M003 | 83.04148.C1H | DIODE SW 1N4148W  SOD-123 | R2_SA;HF_SA; | PANJIT | 1N4148W |  |  | Purchase |  |  |  |  |
| A | B55.01103.M003 | 83.04148.F1H | DIODE SW 1N4148WFL SOD-123 | R2_SA;HF_SA; | YEASHIN | 1N4148WFL |  |  | Purchase |  |  |  |  |
| 3 | B55.01103.M003 | 83.3R903.B3F | DIODE ZEN MMPZ5228BPT SOD-323 | R2_SA;G_SA; | CHENMKO | MMPZ5228BPT | Multiple |  | Purchase | SMT | 1 | PCS | D51 |
| A | B55.01103.M003 | 083.3Z3V9.003F | DIODE ZEN LM3Z3V9T1G SOD-323 | R2_SA;HF_SA; | LRC | LM3Z3V9T1G |  |  | Purchase |  |  |  |  |
| A | B55.01103.M003 | 83.3R903.E3F | DIODE ZEN MM3Z3V9T1G 3.9V SOD-323 | R2_SA;HF_SA; | ON | MM3Z3V9T1G |  |  | Purchase |  |  |  |  |
| 3 | B55.01103.M003 | 83.R5003.H8H | DIODE S.B RB551V30 0.5A 30V SOD-323 | R2_SA;HF_SA;G_SA; | PANJIT | RB551V30 | Multiple |  | Purchase | SMT | 40 | PCS | D1 D10 D11 D12 D13 D14 D15 D16 D17 D18 D19 D2 D20 D21 D22 D23 D24 D25 D26 D27 D28 D29 D3 D30 D31 D32 D33 D34 D35 D36 D4 D47 D48 D49 D5 D50 D6 D7 D8 D9 |
| A | B55.01103.M003 | 83.R5003.T8F | DIODE S.B LRB551V-30T1G SOD-323 | R2_SA;HF_SA; | LRC | LRB551V-30T1G |  |  | Purchase |  |  |  |  |
| 3 | B55.01103.M003 | 83.SMC14.AAG | DIODE TVS SMCJ14A-13-F DO-214AB | R2_SA;HF_SA; | DIODES | SMCJ14A-13-F | Single |  | Purchase | SMT | 2 | PCS | D45 D46 |
| 3 | B55.01103.M003 | 84.02222.V11 | XTOR MMBT2222A NPN SOT-23 | R2_SA;HF_SA;G_SA; | PANJIT | MMBT2222A | Multiple |  | Purchase | SMT | 1 | PCS | Q210 |
| A | B55.01103.M003 | 84.02222.T11 | XTOR MMBT2222A NPN SOT-23(ROHS | R2_SA;HF_SA; | FAIRCHILD | MMBT2222A |  |  | Purchase |  |  |  |  |
| A | B55.01103.M003 | 84.02222.X11 | XTOR MMBT2222ALT1G NPN SOT-23 | R2_SA;HF_SA;G_SA; | ON | MMBT2222ALT1G |  |  | Purchase |  |  |  |  |
| 3 | B55.01103.M003 | 84.03904.T11 | XTOR MMBT3904 NPN SOT-23 | R2_SA;HF_SA;G_SA; | PANJIT | MMBT3904 | Multiple |  | Purchase | SMT | 2 | PCS | Q193 Q200 |
| A | B55.01103.M003 | 84.03904.L06 | XTOR PMBS3904,215 NPN SOT23 (GP) | R2_SA;HF_SA;G_SA; | NEXPERIA | PMBS3904,215 |  |  | Purchase |  |  |  |  |
| A | B55.01103.M003 | 84.T3904.H11 | XTOR LMBT3904LT1G NPN SOT-23 | R2_SA;HF_SA;G_SA; | LRC | LMBT3904LT1G |  |  | Purchase |  |  |  |  |
| 3 | B55.01103.M003 | 84.04407.G37 | FET MOS AO4407AL PC SOIC8(HF) | R2_SA;HF_SA; | AOS | AO4407AL | Multiple |  | Purchase | SMT | 40 | PCS | Q102 Q108 Q114 Q12 Q120 Q126 Q127 Q128 Q130 Q132 Q133 Q138 Q144 Q150 Q156 Q16 Q162 Q168 Q174 Q180 Q186 Q192 Q20 Q24 Q28 Q32 Q36 Q4 Q40 Q44 Q48 Q54 Q60 Q66 Q72 Q78 Q8 Q84 Q90 Q96 |
| A | B55.01103.M003 | 84.04825.A37 | FET MOS SI4825DDY PC SO 8P | R2_SA;HF_SA; | VISHAY | SI4825DDY |  |  | Purchase |  |  |  |  |
| 3 | B55.01103.M003 | 84.08878.A37 | FET MOS FDS8878_G NC SO-8(HF) | R2_SA;HF_SA; | FAIRCHILD | FDS8878_G | Multiple |  | Purchase | SMT | 36 | PCS | Q10 Q100 Q106 Q111 Q118 Q124 Q129 Q135 Q14 Q142 Q148 Q154 Q159 Q165 Q171 Q177 Q18 Q183 Q189 Q2 Q22 Q26 Q30 Q34 Q38 Q42 Q46 Q51 Q57 Q6 Q63 Q70 Q75 Q82 Q87 Q93 |
| A | B55.01103.M003 | 84.04172.037 | FET MOS SI4172DY-T1-GE3 NC SO8 | R2_SA;HF_SA; | VISHAY | SI4172DY-T1-GE3 |  |  | Purchase |  |  |  |  |
| 3 | B55.01103.M003 | 84.2N702.031 | FET MOS 2N7002K-7 NC SOT-23 2KV 300MA | R2_SA;HF_SA; | DIODES | 2N7002K-7 | Single |  | Purchase | SMT | 2 | PCS | Q21 Q25 |
| 3 | B55.01103.M003 | 84.2N702.A3F | FET MOS 2N7002KDW NC SOT-363 ESD 2KV | R2_SA;HF_SA;G_SA; | PANJIT | 2N7002KDW | Multiple |  | Purchase | SMT | 40 | PCS | Q101 Q107 Q11 Q113 Q119 Q125 Q131 Q137 Q143 Q149 Q15 Q155 Q161 Q167 Q173 Q179 Q185 Q19 Q191 Q215 Q216 Q217 Q218 Q23 Q27 Q3 Q31 Q35 Q39 Q43 Q47 Q53 Q59 Q65 Q7 Q71 Q77 Q83 Q89 Q95 |
| A | B55.01103.M003 | 075.063D1.007C | IC FETMOS DMN63D1LDW-7 NC SOT-363 ESD 2K | R2_SA;HF_SA; | DIODES | DMN63D1LDW-7 |  |  | Purchase |  |  |  |  |
| 3 | B55.01103.M003 | 84.2N702.J31 | FET MOS 2N7002K NC SOT-23 ESD 2KV 300MA | R2_SA;HF_SA;G_SA; | PANJIT | 2N7002K | Multiple |  | Purchase | SMT | 31 | PCS | Q209 Q211 Q212 Q213 Q214 Q219 Q220 Q221 Q222 Q223 Q224 Q225 Q226 Q227 Q228 Q229 Q230 Q231 Q232 Q233 Q234 Q235 Q236 Q237 Q238 Q239 Q240 Q241 Q242 Q267 Q268 |
| A | B55.01103.M003 | 084.27002.0L31 | FET MOS T2N7002BK NC SOT-23 | R2_SA;HF_SA; | TOSHIBA | T2N7002BK |  |  | Purchase |  |  |  |  |
| 3 | B55.01103.M003 | 84.M3904.01K | XTOR MMBT3904TT1G NPN SOT-416 | R2_SA;HF_SA; | ON | MMBT3904TT1G | Multiple |  | Purchase | SMT | 1 | PCS | Q5 |
| A | B55.01103.M003 | 84.04617.A1H | XTOR 2SC4617GZTL NPN EMT3 | R2_SA;HF_SA; | ROHM | 2SC4617GZTL |  |  | Purchase |  |  |  |  |
| 3 | B55.01103.M003 | B48.01125.0011 | PCB 16317-1 BRYCE CANYON R.DPB CARD 8L G | R2_SA;HF_SA; | GCE | B48.01125.0011 | Multiple |  | Purchase | SMT | 1 | PCS |  |
| A | B55.01103.M003 | B48.01147.0011 | PCB 16317-1 BRYCE CANYON R.DPB CARD 8L T | R2_SA;HF_SA; | TRIPOD | B48.01147.0011 |  |  | Purchase |  |  |  |  |
